(kicad_pcb
	(version 20260206)
	(generator "pcbnew")
	(generator_version "10.0")
	(general
		(thickness 1.6)
		(legacy_teardrops no)
	)
	(paper "A4")
	(title_block
		(title "01162023_DA0F0TEBIF0_F0T_Expander_BD_F_brd_V02_OCP.brd")
		(comment 1 "Grand Teton / footprints 5445-5451 of 9728")
	)
	(layers
		(0 "F.Cu" signal "TOP")
		(4 "In1.Cu" signal "GND")
		(6 "In2.Cu" signal "VCC")
		(8 "In3.Cu" signal "VCC1")
		(10 "In4.Cu" signal "GND1")
		(12 "In5.Cu" signal "IN1")
		(14 "In6.Cu" signal "GND2")
		(16 "In7.Cu" signal "IN2")
		(18 "In8.Cu" signal "GND3")
		(20 "In9.Cu" signal "IN3")
		(22 "In10.Cu" signal "GND4")
		(24 "In11.Cu" signal "IN4")
		(26 "In12.Cu" signal "GND5")
		(28 "In13.Cu" signal "IN5")
		(30 "In14.Cu" signal "GND6")
		(32 "In15.Cu" signal "IN6")
		(34 "In16.Cu" signal "GND7")
		(2 "B.Cu" signal "BOTTOM")
		(9 "F.Adhes" user "F.Adhesive")
		(11 "B.Adhes" user "B.Adhesive")
		(13 "F.Paste" user "Package Geometry/Pastemask Top")
		(15 "B.Paste" user "Package Geometry/Pastemask Bottom")
		(5 "F.SilkS" user "Ref Des/Silkscreen Top")
		(7 "B.SilkS" user "Ref Des/Silkscreen Bottom")
		(1 "F.Mask" user "Board Geometry/Soldermask Top")
		(3 "B.Mask" user "Board Geometry/Soldermask Bottom")
		(17 "Dwgs.User" user "User.Drawings")
		(19 "Cmts.User" user "User.Comments")
		(21 "Eco1.User" user "User.Eco1")
		(23 "Eco2.User" user "User.Eco2")
		(25 "Edge.Cuts" user "Board Geometry/Outline")
		(27 "Margin" user)
		(31 "F.CrtYd" user "Package Geometry/Place Bound Top")
		(29 "B.CrtYd" user "Package Geometry/Place Bound Bottom")
		(35 "F.Fab" user "Ref Des/Assembly Top")
		(33 "B.Fab" user "Ref Des/Assembly Bottom")
	)
	(footprint ""
		(layer "F.Cu")
		(at 328.041 -82.042 90)
		(property "Reference" "C3993"
			(at 0 0 90)
			(layer "F.SilkS")
			(hide yes)
			(effects
				(font
					(size 1.27 1.27)
				)
			)
		)
		(property "Value" ""
			(at 0 0 90)
			(layer "F.Fab")
			(effects
				(font
					(size 1.27 1.27)
				)
			)
		)
		(duplicate_pad_numbers_are_jumpers no)
		(fp_line
			(start 0.7874 -0.4064)
			(end 0.7874 0.4064)
			(stroke
				(width 0.1524)
				(type default)
			)
			(layer "F.SilkS")
		)
		(fp_line
			(start -0.7874 -0.4064)
			(end 0.7874 -0.4064)
			(stroke
				(width 0.1524)
				(type default)
			)
			(layer "F.SilkS")
		)
		(fp_line
			(start 0.7874 0.4064)
			(end -0.7874 0.4064)
			(stroke
				(width 0.1524)
				(type default)
			)
			(layer "F.SilkS")
		)
		(fp_line
			(start -0.7874 0.4064)
			(end -0.7874 -0.4064)
			(stroke
				(width 0.1524)
				(type default)
			)
			(layer "F.SilkS")
		)
		(fp_line
			(start -0.12065 -0.305054)
			(end -0.12065 -0.2794)
			(stroke
				(width 0.1)
				(type default)
			)
			(layer "F.Fab")
		)
		(fp_line
			(start -0.67945 -0.305054)
			(end -0.12065 -0.305054)
			(stroke
				(width 0.1)
				(type default)
			)
			(layer "F.Fab")
		)
		(fp_line
			(start 0.67945 -0.3048)
			(end 0.67945 0.3048)
			(stroke
				(width 0.1)
				(type default)
			)
			(layer "F.Fab")
		)
		(fp_line
			(start 0.12065 -0.3048)
			(end 0.67945 -0.3048)
			(stroke
				(width 0.1)
				(type default)
			)
			(layer "F.Fab")
		)
		(fp_line
			(start 0.12065 -0.2794)
			(end 0.12065 -0.3048)
			(stroke
				(width 0.1)
				(type default)
			)
			(layer "F.Fab")
		)
		(fp_line
			(start -0.12065 -0.2794)
			(end 0.12065 -0.2794)
			(stroke
				(width 0.1)
				(type default)
			)
			(layer "F.Fab")
		)
		(fp_line
			(start 0.120396 0.2794)
			(end -0.12065 0.2794)
			(stroke
				(width 0.1)
				(type default)
			)
			(layer "F.Fab")
		)
		(fp_line
			(start -0.12065 0.2794)
			(end -0.12065 0.3048)
			(stroke
				(width 0.1)
				(type default)
			)
			(layer "F.Fab")
		)
		(fp_line
			(start 0.67945 0.3048)
			(end 0.120396 0.3048)
			(stroke
				(width 0.1)
				(type default)
			)
			(layer "F.Fab")
		)
		(fp_line
			(start 0.120396 0.3048)
			(end 0.120396 0.2794)
			(stroke
				(width 0.1)
				(type default)
			)
			(layer "F.Fab")
		)
		(fp_line
			(start -0.12065 0.3048)
			(end -0.67945 0.3048)
			(stroke
				(width 0.1)
				(type default)
			)
			(layer "F.Fab")
		)
		(fp_line
			(start -0.67945 0.3048)
			(end -0.67945 -0.305054)
			(stroke
				(width 0.1)
				(type default)
			)
			(layer "F.Fab")
		)
		(pad "1" smd circle
			(at -0.40005 0 90)
			(size 0 0)
			(layers "F.Cu" "F.Mask" "F.Paste")
			(net "GND")
		)
		(pad "2" smd circle
			(at 0.40005 0 90)
			(size 0 0)
			(layers "F.Cu" "F.Mask" "F.Paste")
			(net "P3V3")
		)
	)
	(footprint ""
		(layer "F.Cu")
		(at 117.522498 -293.816786 -90)
		(property "Reference" "PC67"
			(at 0 0 270)
			(layer "F.SilkS")
			(hide yes)
			(effects
				(font
					(size 1.27 1.27)
				)
			)
		)
		(property "Value" ""
			(at 0 0 270)
			(layer "F.Fab")
			(effects
				(font
					(size 1.27 1.27)
				)
			)
		)
		(duplicate_pad_numbers_are_jumpers no)
		(fp_line
			(start -0.7874 0.4064)
			(end -0.7874 -0.4064)
			(stroke
				(width 0.1524)
				(type default)
			)
			(layer "F.SilkS")
		)
		(fp_line
			(start 0.7874 0.4064)
			(end -0.7874 0.4064)
			(stroke
				(width 0.1524)
				(type default)
			)
			(layer "F.SilkS")
		)
		(fp_line
			(start -0.7874 -0.4064)
			(end 0.7874 -0.4064)
			(stroke
				(width 0.1524)
				(type default)
			)
			(layer "F.SilkS")
		)
		(fp_line
			(start 0.7874 -0.4064)
			(end 0.7874 0.4064)
			(stroke
				(width 0.1524)
				(type default)
			)
			(layer "F.SilkS")
		)
		(fp_line
			(start -0.67945 0.3048)
			(end -0.67945 -0.305054)
			(stroke
				(width 0.1)
				(type default)
			)
			(layer "F.Fab")
		)
		(fp_line
			(start -0.12065 0.3048)
			(end -0.67945 0.3048)
			(stroke
				(width 0.1)
				(type default)
			)
			(layer "F.Fab")
		)
		(fp_line
			(start 0.120396 0.3048)
			(end 0.120396 0.2794)
			(stroke
				(width 0.1)
				(type default)
			)
			(layer "F.Fab")
		)
		(fp_line
			(start 0.67945 0.3048)
			(end 0.120396 0.3048)
			(stroke
				(width 0.1)
				(type default)
			)
			(layer "F.Fab")
		)
		(fp_line
			(start -0.12065 0.2794)
			(end -0.12065 0.3048)
			(stroke
				(width 0.1)
				(type default)
			)
			(layer "F.Fab")
		)
		(fp_line
			(start 0.120396 0.2794)
			(end -0.12065 0.2794)
			(stroke
				(width 0.1)
				(type default)
			)
			(layer "F.Fab")
		)
		(fp_line
			(start -0.12065 -0.2794)
			(end 0.12065 -0.2794)
			(stroke
				(width 0.1)
				(type default)
			)
			(layer "F.Fab")
		)
		(fp_line
			(start 0.12065 -0.2794)
			(end 0.12065 -0.3048)
			(stroke
				(width 0.1)
				(type default)
			)
			(layer "F.Fab")
		)
		(fp_line
			(start 0.12065 -0.3048)
			(end 0.67945 -0.3048)
			(stroke
				(width 0.1)
				(type default)
			)
			(layer "F.Fab")
		)
		(fp_line
			(start 0.67945 -0.3048)
			(end 0.67945 0.3048)
			(stroke
				(width 0.1)
				(type default)
			)
			(layer "F.Fab")
		)
		(fp_line
			(start -0.67945 -0.305054)
			(end -0.12065 -0.305054)
			(stroke
				(width 0.1)
				(type default)
			)
			(layer "F.Fab")
		)
		(fp_line
			(start -0.12065 -0.305054)
			(end -0.12065 -0.2794)
			(stroke
				(width 0.1)
				(type default)
			)
			(layer "F.Fab")
		)
		(pad "1" smd circle
			(at -0.40005 0 270)
			(size 0 0)
			(layers "F.Cu" "F.Mask" "F.Paste")
			(net "P0V8_PEX0")
		)
		(pad "2" smd circle
			(at 0.40005 0 270)
			(size 0 0)
			(layers "F.Cu" "F.Mask" "F.Paste")
			(net "GND")
		)
	)
	(footprint ""
		(layer "F.Cu")
		(at 344.612976 -84.169758 180)
		(property "Reference" "R1177"
			(at 0 0 180)
			(layer "F.SilkS")
			(hide yes)
			(effects
				(font
					(size 1.27 1.27)
				)
			)
		)
		(property "Value" ""
			(at 0 0 180)
			(layer "F.Fab")
			(effects
				(font
					(size 1.27 1.27)
				)
			)
		)
		(duplicate_pad_numbers_are_jumpers no)
		(fp_line
			(start 0.7874 0.4064)
			(end -0.7874 0.4064)
			(stroke
				(width 0.1524)
				(type default)
			)
			(layer "F.SilkS")
		)
		(fp_line
			(start 0.67945 0.3048)
			(end 0.120396 0.3048)
			(stroke
				(width 0.1)
				(type default)
			)
			(layer "F.Fab")
		)
		(fp_line
			(start 0.67945 -0.3048)
			(end 0.67945 0.3048)
			(stroke
				(width 0.1)
				(type default)
			)
			(layer "F.Fab")
		)
		(fp_line
			(start 0.12065 -0.2794)
			(end 0.12065 -0.3048)
			(stroke
				(width 0.1)
				(type default)
			)
			(layer "F.Fab")
		)
		(fp_line
			(start 0.12065 -0.3048)
			(end 0.67945 -0.3048)
			(stroke
				(width 0.1)
				(type default)
			)
			(layer "F.Fab")
		)
		(fp_line
			(start 0.120396 0.3048)
			(end 0.120396 0.2794)
			(stroke
				(width 0.1)
				(type default)
			)
			(layer "F.Fab")
		)
		(fp_line
			(start 0.120396 0.2794)
			(end -0.12065 0.2794)
			(stroke
				(width 0.1)
				(type default)
			)
			(layer "F.Fab")
		)
		(fp_line
			(start -0.12065 0.3048)
			(end -0.67945 0.3048)
			(stroke
				(width 0.1)
				(type default)
			)
			(layer "F.Fab")
		)
		(fp_line
			(start -0.12065 0.2794)
			(end -0.12065 0.3048)
			(stroke
				(width 0.1)
				(type default)
			)
			(layer "F.Fab")
		)
		(fp_line
			(start -0.12065 -0.2794)
			(end 0.12065 -0.2794)
			(stroke
				(width 0.1)
				(type default)
			)
			(layer "F.Fab")
		)
		(fp_line
			(start -0.12065 -0.305054)
			(end -0.12065 -0.2794)
			(stroke
				(width 0.1)
				(type default)
			)
			(layer "F.Fab")
		)
		(fp_line
			(start -0.67945 0.3048)
			(end -0.67945 -0.305054)
			(stroke
				(width 0.1)
				(type default)
			)
			(layer "F.Fab")
		)
		(fp_line
			(start -0.67945 -0.305054)
			(end -0.12065 -0.305054)
			(stroke
				(width 0.1)
				(type default)
			)
			(layer "F.Fab")
		)
		(pad "1" smd circle
			(at -0.40005 0 180)
			(size 0 0)
			(layers "F.Cu" "F.Mask" "F.Paste")
			(net "CLK_100M_DB800ZL_SSD11_R_DN")
		)
		(pad "2" smd circle
			(at 0.40005 0 180)
			(size 0 0)
			(layers "F.Cu" "F.Mask" "F.Paste")
			(net "CLK_100M_DB800ZL_SSD11_DN")
		)
	)
	(footprint ""
		(layer "F.Cu")
		(at 46.947328 -19.33956)
		(property "Reference" "C3882"
			(at 0 0 0)
			(layer "F.SilkS")
			(hide yes)
			(effects
				(font
					(size 1.27 1.27)
				)
			)
		)
		(property "Value" ""
			(at 0 0 0)
			(layer "F.Fab")
			(effects
				(font
					(size 1.27 1.27)
				)
			)
		)
		(duplicate_pad_numbers_are_jumpers no)
		(fp_line
			(start -0.7874 -0.4064)
			(end 0.7874 -0.4064)
			(stroke
				(width 0.1524)
				(type default)
			)
			(layer "F.SilkS")
		)
		(fp_line
			(start -0.7874 0.4064)
			(end -0.7874 -0.4064)
			(stroke
				(width 0.1524)
				(type default)
			)
			(layer "F.SilkS")
		)
		(fp_line
			(start 0.7874 -0.4064)
			(end 0.7874 0.4064)
			(stroke
				(width 0.1524)
				(type default)
			)
			(layer "F.SilkS")
		)
		(fp_line
			(start 0.7874 0.4064)
			(end -0.7874 0.4064)
			(stroke
				(width 0.1524)
				(type default)
			)
			(layer "F.SilkS")
		)
		(fp_line
			(start -0.67945 -0.305054)
			(end -0.12065 -0.305054)
			(stroke
				(width 0.1)
				(type default)
			)
			(layer "F.Fab")
		)
		(fp_line
			(start -0.67945 0.3048)
			(end -0.67945 -0.305054)
			(stroke
				(width 0.1)
				(type default)
			)
			(layer "F.Fab")
		)
		(fp_line
			(start -0.12065 -0.305054)
			(end -0.12065 -0.2794)
			(stroke
				(width 0.1)
				(type default)
			)
			(layer "F.Fab")
		)
		(fp_line
			(start -0.12065 -0.2794)
			(end 0.12065 -0.2794)
			(stroke
				(width 0.1)
				(type default)
			)
			(layer "F.Fab")
		)
		(fp_line
			(start -0.12065 0.2794)
			(end -0.12065 0.3048)
			(stroke
				(width 0.1)
				(type default)
			)
			(layer "F.Fab")
		)
		(fp_line
			(start -0.12065 0.3048)
			(end -0.67945 0.3048)
			(stroke
				(width 0.1)
				(type default)
			)
			(layer "F.Fab")
		)
		(fp_line
			(start 0.120396 0.2794)
			(end -0.12065 0.2794)
			(stroke
				(width 0.1)
				(type default)
			)
			(layer "F.Fab")
		)
		(fp_line
			(start 0.120396 0.3048)
			(end 0.120396 0.2794)
			(stroke
				(width 0.1)
				(type default)
			)
			(layer "F.Fab")
		)
		(fp_line
			(start 0.12065 -0.3048)
			(end 0.67945 -0.3048)
			(stroke
				(width 0.1)
				(type default)
			)
			(layer "F.Fab")
		)
		(fp_line
			(start 0.12065 -0.2794)
			(end 0.12065 -0.3048)
			(stroke
				(width 0.1)
				(type default)
			)
			(layer "F.Fab")
		)
		(fp_line
			(start 0.67945 -0.3048)
			(end 0.67945 0.3048)
			(stroke
				(width 0.1)
				(type default)
			)
			(layer "F.Fab")
		)
		(fp_line
			(start 0.67945 0.3048)
			(end 0.120396 0.3048)
			(stroke
				(width 0.1)
				(type default)
			)
			(layer "F.Fab")
		)
		(pad "1" smd circle
			(at -0.40005 0)
			(size 0 0)
			(layers "F.Cu" "F.Mask" "F.Paste")
			(net "P12V_SSD1")
		)
		(pad "2" smd circle
			(at 0.40005 0)
			(size 0 0)
			(layers "F.Cu" "F.Mask" "F.Paste")
			(net "GND")
		)
	)
	(footprint ""
		(layer "F.Cu")
		(at 61.19495 -59.577986 90)
		(property "Reference" "PC530"
			(at 0 0 90)
			(layer "F.SilkS")
			(hide yes)
			(effects
				(font
					(size 1.27 1.27)
				)
			)
		)
		(property "Value" ""
			(at 0 0 90)
			(layer "F.Fab")
			(effects
				(font
					(size 1.27 1.27)
				)
			)
		)
		(duplicate_pad_numbers_are_jumpers no)
		(fp_line
			(start 0.7874 -0.4064)
			(end 0.7874 0.4064)
			(stroke
				(width 0.1524)
				(type default)
			)
			(layer "F.SilkS")
		)
		(fp_line
			(start -0.7874 -0.4064)
			(end 0.7874 -0.4064)
			(stroke
				(width 0.1524)
				(type default)
			)
			(layer "F.SilkS")
		)
		(fp_line
			(start 0.7874 0.4064)
			(end -0.7874 0.4064)
			(stroke
				(width 0.1524)
				(type default)
			)
			(layer "F.SilkS")
		)
		(fp_line
			(start -0.7874 0.4064)
			(end -0.7874 -0.4064)
			(stroke
				(width 0.1524)
				(type default)
			)
			(layer "F.SilkS")
		)
		(fp_line
			(start -0.12065 -0.305054)
			(end -0.12065 -0.2794)
			(stroke
				(width 0.1)
				(type default)
			)
			(layer "F.Fab")
		)
		(fp_line
			(start -0.67945 -0.305054)
			(end -0.12065 -0.305054)
			(stroke
				(width 0.1)
				(type default)
			)
			(layer "F.Fab")
		)
		(fp_line
			(start 0.67945 -0.3048)
			(end 0.67945 0.3048)
			(stroke
				(width 0.1)
				(type default)
			)
			(layer "F.Fab")
		)
		(fp_line
			(start 0.12065 -0.3048)
			(end 0.67945 -0.3048)
			(stroke
				(width 0.1)
				(type default)
			)
			(layer "F.Fab")
		)
		(fp_line
			(start 0.12065 -0.2794)
			(end 0.12065 -0.3048)
			(stroke
				(width 0.1)
				(type default)
			)
			(layer "F.Fab")
		)
		(fp_line
			(start -0.12065 -0.2794)
			(end 0.12065 -0.2794)
			(stroke
				(width 0.1)
				(type default)
			)
			(layer "F.Fab")
		)
		(fp_line
			(start 0.120396 0.2794)
			(end -0.12065 0.2794)
			(stroke
				(width 0.1)
				(type default)
			)
			(layer "F.Fab")
		)
		(fp_line
			(start -0.12065 0.2794)
			(end -0.12065 0.3048)
			(stroke
				(width 0.1)
				(type default)
			)
			(layer "F.Fab")
		)
		(fp_line
			(start 0.67945 0.3048)
			(end 0.120396 0.3048)
			(stroke
				(width 0.1)
				(type default)
			)
			(layer "F.Fab")
		)
		(fp_line
			(start 0.120396 0.3048)
			(end 0.120396 0.2794)
			(stroke
				(width 0.1)
				(type default)
			)
			(layer "F.Fab")
		)
		(fp_line
			(start -0.12065 0.3048)
			(end -0.67945 0.3048)
			(stroke
				(width 0.1)
				(type default)
			)
			(layer "F.Fab")
		)
		(fp_line
			(start -0.67945 0.3048)
			(end -0.67945 -0.305054)
			(stroke
				(width 0.1)
				(type default)
			)
			(layer "F.Fab")
		)
		(pad "1" smd circle
			(at -0.40005 0 90)
			(size 0 0)
			(layers "F.Cu" "F.Mask" "F.Paste")
			(net "P3V3_SSD2_SS")
		)
		(pad "2" smd circle
			(at 0.40005 0 90)
			(size 0 0)
			(layers "F.Cu" "F.Mask" "F.Paste")
			(net "GND")
		)
	)
	(footprint ""
		(layer "F.Cu")
		(at 111.836708 -350.098614 90)
		(property "Reference" "C356"
			(at 0 0 90)
			(layer "F.SilkS")
			(hide yes)
			(effects
				(font
					(size 1.27 1.27)
				)
			)
		)
		(property "Value" ""
			(at 0 0 90)
			(layer "F.Fab")
			(effects
				(font
					(size 1.27 1.27)
				)
			)
		)
		(duplicate_pad_numbers_are_jumpers no)
		(fp_line
			(start 0.299974 -0.150114)
			(end 0.299974 0.150114)
			(stroke
				(width 0.1)
				(type default)
			)
			(layer "F.Fab")
		)
		(fp_line
			(start -0.299974 -0.150114)
			(end 0.299974 -0.150114)
			(stroke
				(width 0.1)
				(type default)
			)
			(layer "F.Fab")
		)
		(fp_line
			(start 0.299974 0.150114)
			(end -0.299974 0.150114)
			(stroke
				(width 0.1)
				(type default)
			)
			(layer "F.Fab")
		)
		(fp_line
			(start -0.299974 0.150114)
			(end -0.299974 -0.150114)
			(stroke
				(width 0.1)
				(type default)
			)
			(layer "F.Fab")
		)
		(pad "1" smd rect
			(at -0.2667 0 90)
			(size 0.3048 0.381)
			(layers "F.Cu" "F.Mask" "F.Paste")
			(net "P5E_PEX1_STN6_TX_DP<103>")
		)
		(pad "2" smd rect
			(at 0.2667 0 90)
			(size 0.3048 0.381)
			(layers "F.Cu" "F.Mask" "F.Paste")
			(net "P5E_PEX1_STN6_TX_C_DP<103>")
		)
	)
	(footprint ""
		(layer "F.Cu")
		(at 428.319438 -122.270266 180)
		(property "Reference" "C661"
			(at 0 0 180)
			(layer "F.SilkS")
			(hide yes)
			(effects
				(font
					(size 1.27 1.27)
				)
			)
		)
		(property "Value" ""
			(at 0 0 180)
			(layer "F.Fab")
			(effects
				(font
					(size 1.27 1.27)
				)
			)
		)
		(duplicate_pad_numbers_are_jumpers no)
		(fp_line
			(start 0.299974 0.150114)
			(end -0.299974 0.150114)
			(stroke
				(width 0.1)
				(type default)
			)
			(layer "F.Fab")
		)
		(fp_line
			(start 0.299974 -0.150114)
			(end 0.299974 0.150114)
			(stroke
				(width 0.1)
				(type default)
			)
			(layer "F.Fab")
		)
		(fp_line
			(start -0.299974 0.150114)
			(end -0.299974 -0.150114)
			(stroke
				(width 0.1)
				(type default)
			)
			(layer "F.Fab")
		)
		(fp_line
			(start -0.299974 -0.150114)
			(end 0.299974 -0.150114)
			(stroke
				(width 0.1)
				(type default)
			)
			(layer "F.Fab")
		)
		(pad "1" smd rect
			(at -0.2667 0 180)
			(size 0.3048 0.381)
			(layers "F.Cu" "F.Mask" "F.Paste")
			(net "P5E_PEX3_STN0_TX_DN<2>")
		)
		(pad "2" smd rect
			(at 0.2667 0 180)
			(size 0.3048 0.381)
			(layers "F.Cu" "F.Mask" "F.Paste")
			(net "P5E_PEX3_STN0_TX_C_DN<2>")
		)
	)
)
